# T6G (Grand Teton) — schematic netlist excerpt (pin names and nets, part order shuffled) for the footprints in the layout excerpt that follows; sources: Cadence DE-HDL packaged netlist, KiCad conversion of 04192023_DAF0TMB3IC0_F0TG_MB_C_brd_V02_OCP.brd

C1840  Q_CAP  0.1UF 25V 10% X7R  pkg 0402  page 132 : A = P3V3_AUX ; B = GND

PL44  Q_INDUCTOR4P_14  150NH IND  pkg L_TLM117513Q-151QL_11X7-5XA  page 219
  \1\  = SW_PVDDCR_CPU1_P1_SW3
  \2\  = IND_CPU1_P1_CPL2
  \3\  = IND_CPU1_P1_CPL3
  \4\  = PVDDCR_CPU1_P1

(kicad_pcb
	(version 20260206)
	(generator "pcbnew")
	(generator_version "10.0")
	(general
		(thickness 1.6)
		(legacy_teardrops no)
	)
	(paper "A4")
	(title_block
		(title "04192023_DAF0TMB3IC0_F0TG_MB_C_brd_V02_OCP.brd")
		(comment 1 "Grand Teton / footprints 3088-3089 of 8354")
	)
	(layers
		(0 "F.Cu" signal "TOP")
		(4 "In1.Cu" signal "GND")
		(6 "In2.Cu" signal "IN1")
		(8 "In3.Cu" signal "GND1")
		(10 "In4.Cu" signal "IN2")
		(12 "In5.Cu" signal "GND2")
		(14 "In6.Cu" signal "IN3")
		(16 "In7.Cu" signal "GND3")
		(18 "In8.Cu" signal "VCC")
		(20 "In9.Cu" signal "VCC1")
		(22 "In10.Cu" signal "GND4")
		(24 "In11.Cu" signal "IN4")
		(26 "In12.Cu" signal "GND5")
		(28 "In13.Cu" signal "IN5")
		(30 "In14.Cu" signal "GND6")
		(32 "In15.Cu" signal "IN6")
		(34 "In16.Cu" signal "GND7")
		(2 "B.Cu" signal "BOTTOM")
		(9 "F.Adhes" user "F.Adhesive")
		(11 "B.Adhes" user "B.Adhesive")
		(13 "F.Paste" user "Package Geometry/Pastemask Top")
		(15 "B.Paste" user "Package Geometry/Pastemask Bottom")
		(5 "F.SilkS" user "Ref Des/Silkscreen Top")
		(7 "B.SilkS" user "Ref Des/Silkscreen Bottom")
		(1 "F.Mask" user "Board Geometry/Soldermask Top")
		(3 "B.Mask" user "Board Geometry/Soldermask Bottom")
		(17 "Dwgs.User" user "User.Drawings")
		(19 "Cmts.User" user "User.Comments")
		(21 "Eco1.User" user "User.Eco1")
		(23 "Eco2.User" user "User.Eco2")
		(25 "Edge.Cuts" user "Board Geometry/Outline")
		(27 "Margin" user)
		(31 "F.CrtYd" user "Package Geometry/Place Bound Top")
		(29 "B.CrtYd" user "Package Geometry/Place Bound Bottom")
		(35 "F.Fab" user "Ref Des/Assembly Top")
		(33 "B.Fab" user "Ref Des/Assembly Bottom")
	)
	(footprint ""
		(layer "F.Cu")
		(at 461.957928 -94.317566)
		(property "Reference" "C1840"
			(at 0 0 0)
			(layer "F.SilkS")
			(hide yes)
			(effects
				(font
					(size 1.27 1.27)
				)
			)
		)
		(property "Value" ""
			(at 0 0 0)
			(layer "F.Fab")
			(effects
				(font
					(size 1.27 1.27)
				)
			)
		)
		(duplicate_pad_numbers_are_jumpers no)
		(fp_line
			(start -0.7874 -0.4064)
			(end 0.7874 -0.4064)
			(stroke
				(width 0.1524)
				(type default)
			)
			(layer "F.SilkS")
		)
		(fp_line
			(start -0.7874 0.4064)
			(end -0.7874 -0.4064)
			(stroke
				(width 0.1524)
				(type default)
			)
			(layer "F.SilkS")
		)
		(fp_line
			(start 0.7874 -0.4064)
			(end 0.7874 0.4064)
			(stroke
				(width 0.1524)
				(type default)
			)
			(layer "F.SilkS")
		)
		(fp_line
			(start 0.7874 0.4064)
			(end -0.7874 0.4064)
			(stroke
				(width 0.1524)
				(type default)
			)
			(layer "F.SilkS")
		)
		(fp_line
			(start -0.67945 -0.305054)
			(end -0.12065 -0.305054)
			(stroke
				(width 0.1)
				(type default)
			)
			(layer "F.Fab")
		)
		(fp_line
			(start -0.67945 0.3048)
			(end -0.67945 -0.305054)
			(stroke
				(width 0.1)
				(type default)
			)
			(layer "F.Fab")
		)
		(fp_line
			(start -0.12065 -0.305054)
			(end -0.12065 -0.2794)
			(stroke
				(width 0.1)
				(type default)
			)
			(layer "F.Fab")
		)
		(fp_line
			(start -0.12065 -0.2794)
			(end 0.12065 -0.2794)
			(stroke
				(width 0.1)
				(type default)
			)
			(layer "F.Fab")
		)
		(fp_line
			(start -0.12065 0.2794)
			(end -0.12065 0.3048)
			(stroke
				(width 0.1)
				(type default)
			)
			(layer "F.Fab")
		)
		(fp_line
			(start -0.12065 0.3048)
			(end -0.67945 0.3048)
			(stroke
				(width 0.1)
				(type default)
			)
			(layer "F.Fab")
		)
		(fp_line
			(start 0.120396 0.2794)
			(end -0.12065 0.2794)
			(stroke
				(width 0.1)
				(type default)
			)
			(layer "F.Fab")
		)
		(fp_line
			(start 0.120396 0.3048)
			(end 0.120396 0.2794)
			(stroke
				(width 0.1)
				(type default)
			)
			(layer "F.Fab")
		)
		(fp_line
			(start 0.12065 -0.3048)
			(end 0.67945 -0.3048)
			(stroke
				(width 0.1)
				(type default)
			)
			(layer "F.Fab")
		)
		(fp_line
			(start 0.12065 -0.2794)
			(end 0.12065 -0.3048)
			(stroke
				(width 0.1)
				(type default)
			)
			(layer "F.Fab")
		)
		(fp_line
			(start 0.67945 -0.3048)
			(end 0.67945 0.3048)
			(stroke
				(width 0.1)
				(type default)
			)
			(layer "F.Fab")
		)
		(fp_line
			(start 0.67945 0.3048)
			(end 0.120396 0.3048)
			(stroke
				(width 0.1)
				(type default)
			)
			(layer "F.Fab")
		)
		(pad "1" smd circle
			(at -0.40005 0)
			(size 0 0)
			(layers "F.Cu" "F.Mask" "F.Paste")
			(net "P3V3_AUX")
		)
		(pad "2" smd circle
			(at 0.40005 0)
			(size 0 0)
			(layers "F.Cu" "F.Mask" "F.Paste")
			(net "GND")
		)
	)
	(footprint ""
		(layer "F.Cu")
		(at 70.52691 -325.682864)
		(property "Reference" "PL44"
			(at 2.853944 -16.649446 0)
			(unlocked yes)
			(layer "F.SilkS")
			(effects
				(font
					(size 0.7874 0.5842)
					(thickness 0.1524)
				)
				(justify left)
			)
		)
		(property "Value" ""
			(at 0 0 0)
			(layer "F.Fab")
			(effects
				(font
					(size 1.27 1.27)
				)
			)
		)
		(duplicate_pad_numbers_are_jumpers no)
		(fp_line
			(start -3.750056 -5.500116)
			(end -2.393442 -5.500116)
			(stroke
				(width 0.1524)
				(type default)
			)
			(layer "F.SilkS")
		)
		(fp_line
			(start -3.750056 5.500116)
			(end -3.750056 -5.500116)
			(stroke
				(width 0.1524)
				(type default)
			)
			(layer "F.SilkS")
		)
		(fp_line
			(start -2.393442 5.500116)
			(end -3.750056 5.500116)
			(stroke
				(width 0.1524)
				(type default)
			)
			(layer "F.SilkS")
		)
		(fp_line
			(start 2.393442 5.500116)
			(end 3.750056 5.500116)
			(stroke
				(width 0.1524)
				(type default)
			)
			(layer "F.SilkS")
		)
		(fp_line
			(start 3.750056 -5.500116)
			(end 2.393442 -5.500116)
			(stroke
				(width 0.1524)
				(type default)
			)
			(layer "F.SilkS")
		)
		(fp_line
			(start 3.750056 5.500116)
			(end 3.750056 -5.500116)
			(stroke
				(width 0.1524)
				(type default)
			)
			(layer "F.SilkS")
		)
		(fp_poly
			(pts
				(xy -3.9116 -4.249928) (xy -4.9276 -3.741928) (xy -4.9276 -4.757928)
			)
			(stroke
				(width 0)
				(type default)
			)
			(fill yes)
			(layer "F.SilkS")
		)
		(fp_line
			(start -3.750056 -5.500116)
			(end -3.750056 5.500116)
			(stroke
				(width 0.1)
				(type default)
			)
			(layer "F.Fab")
		)
		(fp_line
			(start -3.750056 5.500116)
			(end 3.750056 5.500116)
			(stroke
				(width 0.1)
				(type default)
			)
			(layer "F.Fab")
		)
		(fp_line
			(start 3.750056 -5.500116)
			(end -3.750056 -5.500116)
			(stroke
				(width 0.1)
				(type default)
			)
			(layer "F.Fab")
		)
		(fp_line
			(start 3.750056 5.500116)
			(end 3.750056 -5.500116)
			(stroke
				(width 0.1)
				(type default)
			)
			(layer "F.Fab")
		)
		(fp_poly
			(pts
				(xy -4.9276 -4.757928) (xy -4.9276 -3.741928) (xy -3.9116 -4.249928)
			)
			(stroke
				(width 0)
				(type default)
			)
			(fill yes)
			(layer "F.Fab")
		)
		(pad "1" smd rect
			(at 0 -4.249928 270)
			(size 2.413 4.5212)
			(layers "F.Cu" "F.Mask" "F.Paste")
			(net "SW_PVDDCR_CPU1_P1_SW3")
		)
		(pad "2" smd rect
			(at 0 -1.175004 270)
			(size 1.3716 4.5212)
			(layers "F.Cu" "F.Mask" "F.Paste")
			(net "IND_CPU1_P1_CPL2")
		)
		(pad "3" smd rect
			(at 0 1.175004 270)
			(size 1.3716 4.5212)
			(layers "F.Cu" "F.Mask" "F.Paste")
			(net "IND_CPU1_P1_CPL3")
		)
		(pad "4" smd rect
			(at 0 4.249928 270)
			(size 2.413 4.5212)
			(layers "F.Cu" "F.Mask" "F.Paste")
			(net "PVDDCR_CPU1_P1")
		)
	)
)
